# BASEBOARD_FAB2 (Tioga Pass) — schematic netlist excerpt (pin names and nets, part order shuffled) for the footprints in the layout excerpt that follows; sources: Cadence DE-HDL packaged netlist, KiCad conversion of Wiwynn_Tioga_Pass_MB.brd

R4G22  RES  1.00K 1% CHIP  pkg 0402  page 98 : A = M_C_VREF ; B = GND
C7B22  CAP_A  22.0UF 4V 20% X6S  pkg 0603V  page 131 : A = P1V05_PCH_STBY ; B = GND
C7C14  CAP  0.220UF 16V 10% X7R  pkg 0402  page 212 : A = VR_PVCCIO_CPU0_PH1_BOOT ; B = VR_PVCCIO_CPU0_PH1_PHASE

(kicad_pcb
	(version 20260206)
	(generator "pcbnew")
	(generator_version "10.0")
	(general
		(thickness 1.6)
		(legacy_teardrops no)
	)
	(paper "A4")
	(title_block
		(title "Wiwynn_Tioga_Pass_MB.brd")
		(comment 1 "Tioga Pass / footprints 1478-1480 of 4770")
	)
	(layers
		(0 "F.Cu" signal "TOP")
		(4 "In1.Cu" signal "L2GND")
		(6 "In2.Cu" signal "L3")
		(8 "In3.Cu" signal "L4GND")
		(10 "In4.Cu" signal "L5")
		(12 "In5.Cu" signal "L6GND")
		(14 "In6.Cu" signal "L7VCC")
		(16 "In7.Cu" signal "L8VCC")
		(18 "In8.Cu" signal "L9GND")
		(20 "In9.Cu" signal "L10")
		(22 "In10.Cu" signal "L11GND")
		(24 "In11.Cu" signal "L12")
		(26 "In12.Cu" signal "L13GND")
		(2 "B.Cu" signal "BOTTOM")
		(9 "F.Adhes" user "F.Adhesive")
		(11 "B.Adhes" user "B.Adhesive")
		(13 "F.Paste" user "Package Geometry/Pastemask Top")
		(15 "B.Paste" user "Package Geometry/Pastemask Bottom")
		(5 "F.SilkS" user "Ref Des/Silkscreen Top")
		(7 "B.SilkS" user "Ref Des/Silkscreen Bottom")
		(1 "F.Mask" user "Board Geometry/Soldermask Top")
		(3 "B.Mask" user "Board Geometry/Soldermask Bottom")
		(17 "Dwgs.User" user "User.Drawings")
		(19 "Cmts.User" user "User.Comments")
		(21 "Eco1.User" user "User.Eco1")
		(23 "Eco2.User" user "User.Eco2")
		(25 "Edge.Cuts" user "Board Geometry/Outline")
		(27 "Margin" user)
		(31 "F.CrtYd" user "Package Geometry/Place Bound Top")
		(29 "B.CrtYd" user "Package Geometry/Place Bound Bottom")
		(35 "F.Fab" user "Ref Des/Assembly Top")
		(33 "B.Fab" user "Ref Des/Assembly Bottom")
	)
	(footprint ""
		(layer "F.Cu")
		(at 369.7224 -130.429 180)
		(property "Reference" "C7B22"
			(at 0 0 180)
			(layer "F.SilkS")
			(hide yes)
			(effects
				(font
					(size 1.27 1.27)
				)
			)
		)
		(property "Value" ""
			(at 0 0 180)
			(layer "F.Fab")
			(effects
				(font
					(size 1.27 1.27)
				)
			)
		)
		(duplicate_pad_numbers_are_jumpers no)
		(fp_poly
			(pts
				(xy -0.4953 -0.2032) (xy 0.4953 -0.2032) (xy 0.4953 1.6002) (xy -0.4953 1.6002)
			)
			(stroke
				(width 0)
				(type default)
			)
			(fill no)
			(layer "F.CrtYd")
		)
		(fp_line
			(start 0.4953 1.6002)
			(end -0.4953 1.6002)
			(stroke
				(width 0.1)
				(type default)
			)
			(layer "F.Fab")
		)
		(fp_line
			(start 0.4953 -0.2032)
			(end 0.4953 1.6002)
			(stroke
				(width 0.1)
				(type default)
			)
			(layer "F.Fab")
		)
		(fp_line
			(start -0.4953 1.6002)
			(end -0.4953 -0.2032)
			(stroke
				(width 0.1)
				(type default)
			)
			(layer "F.Fab")
		)
		(fp_line
			(start -0.4953 -0.2032)
			(end 0.4953 -0.2032)
			(stroke
				(width 0.1)
				(type default)
			)
			(layer "F.Fab")
		)
		(pad "1" smd rect
			(at 0 0 180)
			(size 0.762 0.889)
			(layers "F.Cu" "F.Mask" "F.Paste")
			(net "P1V05_PCH_STBY")
		)
		(pad "2" smd rect
			(at 0 1.397 180)
			(size 0.762 0.889)
			(layers "F.Cu" "F.Mask" "F.Paste")
			(net "GND")
		)
		(zone
			(layer "F.Cu")
			(hatch none 0.5)
			(connect_pads
				(clearance 0)
			)
			(min_thickness 0.25)
			(keepout
				(tracks not_allowed)
				(vias allowed)
				(pads allowed)
				(copperpour not_allowed)
				(footprints allowed)
			)
			(placement
				(enabled no)
				(sheetname "")
			)
			(fill
				(thermal_gap 0.5)
				(thermal_bridge_width 0.5)
				(island_removal_mode 0)
			)
			(polygon
				(pts
					(xy 370.1034 -130.8735) (xy 369.3414 -130.8735) (xy 369.3414 -131.3815) (xy 370.1034 -131.3815)
				)
			)
		)
	)
	(footprint ""
		(layer "F.Cu")
		(at 352.153982 -95.497904 -90)
		(property "Reference" "C7C14"
			(at 0 0 270)
			(layer "F.SilkS")
			(hide yes)
			(effects
				(font
					(size 1.27 1.27)
				)
			)
		)
		(property "Value" ""
			(at 0 0 270)
			(layer "F.Fab")
			(effects
				(font
					(size 1.27 1.27)
				)
			)
		)
		(duplicate_pad_numbers_are_jumpers no)
		(fp_poly
			(pts
				(xy 0.3048 -0.1016) (xy 0.3048 0.9906) (xy -0.3048 0.9906) (xy -0.3048 -0.1016)
			)
			(stroke
				(width 0)
				(type default)
			)
			(fill no)
			(layer "F.CrtYd")
		)
		(fp_line
			(start -0.3048 0.9906)
			(end 0.3048 0.9906)
			(stroke
				(width 0.1)
				(type default)
			)
			(layer "F.Fab")
		)
		(fp_line
			(start 0.3048 0.9906)
			(end 0.3048 -0.1016)
			(stroke
				(width 0.1)
				(type default)
			)
			(layer "F.Fab")
		)
		(fp_line
			(start -0.3048 -0.1016)
			(end -0.3048 0.9906)
			(stroke
				(width 0.1)
				(type default)
			)
			(layer "F.Fab")
		)
		(fp_line
			(start 0.3048 -0.1016)
			(end -0.3048 -0.1016)
			(stroke
				(width 0.1)
				(type default)
			)
			(layer "F.Fab")
		)
		(pad "1" smd rect
			(at 0 0 270)
			(size 0.508 0.508)
			(layers "F.Cu" "F.Mask" "F.Paste")
			(net "VR_PVCCIO_CPU0_PH1_BOOT")
		)
		(pad "2" smd rect
			(at 0 0.889 270)
			(size 0.508 0.508)
			(layers "F.Cu" "F.Mask" "F.Paste")
			(net "VR_PVCCIO_CPU0_PH1_PHASE")
		)
		(zone
			(layer "F.Cu")
			(hatch none 0.5)
			(connect_pads
				(clearance 0)
			)
			(min_thickness 0.25)
			(keepout
				(tracks not_allowed)
				(vias allowed)
				(pads allowed)
				(copperpour not_allowed)
				(footprints allowed)
			)
			(placement
				(enabled no)
				(sheetname "")
			)
			(fill
				(thermal_gap 0.5)
				(thermal_bridge_width 0.5)
				(island_removal_mode 0)
			)
			(polygon
				(pts
					(xy 351.518982 -95.751904) (xy 351.518982 -95.243904) (xy 351.899982 -95.243904) (xy 351.899982 -95.751904)
				)
			)
		)
		(zone
			(layer "F.Cu")
			(hatch none 0.5)
			(connect_pads
				(clearance 0)
			)
			(min_thickness 0.25)
			(keepout
				(tracks allowed)
				(vias not_allowed)
				(pads allowed)
				(copperpour not_allowed)
				(footprints allowed)
			)
			(placement
				(enabled no)
				(sheetname "")
			)
			(fill
				(thermal_gap 0.5)
				(thermal_bridge_width 0.5)
				(island_removal_mode 0)
			)
			(polygon
				(pts
					(xy 351.899982 -95.751904) (xy 351.899982 -95.243904) (xy 351.518982 -95.243904) (xy 351.518982 -95.751904)
				)
			)
		)
	)
	(footprint ""
		(layer "F.Cu")
		(at 194.564 -2.8575 180)
		(property "Reference" "R4G22"
			(at 0 0 180)
			(layer "F.SilkS")
			(hide yes)
			(effects
				(font
					(size 1.27 1.27)
				)
			)
		)
		(property "Value" ""
			(at 0 0 180)
			(layer "F.Fab")
			(effects
				(font
					(size 1.27 1.27)
				)
			)
		)
		(duplicate_pad_numbers_are_jumpers no)
		(fp_poly
			(pts
				(xy -0.2794 -0.1016) (xy 0.2794 -0.1016) (xy 0.2794 0.9906) (xy -0.2794 0.9906)
			)
			(stroke
				(width 0)
				(type default)
			)
			(fill no)
			(layer "F.CrtYd")
		)
		(fp_line
			(start 0.2794 0.9906)
			(end 0.2794 -0.1016)
			(stroke
				(width 0.1)
				(type default)
			)
			(layer "F.Fab")
		)
		(fp_line
			(start 0.2794 -0.1016)
			(end -0.2794 -0.1016)
			(stroke
				(width 0.1)
				(type default)
			)
			(layer "F.Fab")
		)
		(fp_line
			(start -0.2794 0.9906)
			(end 0.2794 0.9906)
			(stroke
				(width 0.1)
				(type default)
			)
			(layer "F.Fab")
		)
		(fp_line
			(start -0.2794 -0.1016)
			(end -0.2794 0.9906)
			(stroke
				(width 0.1)
				(type default)
			)
			(layer "F.Fab")
		)
		(pad "1" smd rect
			(at 0 0 180)
			(size 0.508 0.508)
			(layers "F.Cu" "F.Mask" "F.Paste")
			(net "M_C_VREF")
		)
		(pad "2" smd rect
			(at 0 0.889 180)
			(size 0.508 0.508)
			(layers "F.Cu" "F.Mask" "F.Paste")
			(net "GND")
		)
		(zone
			(layer "F.Cu")
			(hatch none 0.5)
			(connect_pads
				(clearance 0)
			)
			(min_thickness 0.25)
			(keepout
				(tracks not_allowed)
				(vias allowed)
				(pads allowed)
				(copperpour not_allowed)
				(footprints allowed)
			)
			(placement
				(enabled no)
				(sheetname "")
			)
			(fill
				(thermal_gap 0.5)
				(thermal_bridge_width 0.5)
				(island_removal_mode 0)
			)
			(polygon
				(pts
					(xy 194.818 -3.4925) (xy 194.31 -3.4925) (xy 194.31 -3.1115) (xy 194.818 -3.1115)
				)
			)
		)
		(zone
			(layer "F.Cu")
			(hatch none 0.5)
			(connect_pads
				(clearance 0)
			)
			(min_thickness 0.25)
			(keepout
				(tracks allowed)
				(vias not_allowed)
				(pads allowed)
				(copperpour not_allowed)
				(footprints allowed)
			)
			(placement
				(enabled no)
				(sheetname "")
			)
			(fill
				(thermal_gap 0.5)
				(thermal_bridge_width 0.5)
				(island_removal_mode 0)
			)
			(polygon
				(pts
					(xy 194.818 -3.1115) (xy 194.31 -3.1115) (xy 194.31 -3.4925) (xy 194.818 -3.4925)
				)
			)
		)
	)
)
